FILE_TYPE = MULTI_PHYS_TABLE;

PART 'TP_TDR_4P_FTS'

{========================================================================================}
:VALUE           | PACK_TYPE | MATERIAL | PART_NUMBER    = STANDARD         | LIFECYCLE        | ENVCOMP   | PART_NUMBER | JEDEC_TYPE        | CLASS | DESCRIPTION                      | HEIGHT       | COMPONENT_TYPE | LPID | STATUS | RPL   | AML   | DAYS       ;
{========================================================================================}
 'TP_TDR_4P_DIP' | 'TH'      | 'EMPTY'  | 'TP15'(!)      = ''               | ''               | '(Error)' | 'N_A'       |'MPKT4_H025P0200'| 'IO'  | 'DIFF_TEST_PAD DIP FOR FTS ONLY' | '0.00001 IN' | 'PSEUDO'       | ''   | '???'  | '???' | '???' | '20110210'
 'TP_TDR_4P_SMD' | 'TH'      | 'EMPTY'  | 'TP16'(!)      = ''               | ''               | '(Error)' | 'N_A'       |'MPKT4_P0200'| 'IO'  | 'DIFF_TEST_PAD SMD FOR FTS ONLY' | '0.00001 IN' | 'PSEUDO'       | ''   | '???'  | '???' | '???' | '20110210'

END_PART

END.

